(kicad_pcb
	(version 20260206)
	(generator "pcbnew")
	(generator_version "10.0")
	(general
		(thickness 1.6)
		(legacy_teardrops no)
	)
	(paper "A4")
	(title_block
		(title "timecard-production-celestica-r4006 — R4006-B0001-02_R01.brd")
		(comment 1 "Time Appliance Project (Time Card) / footprints 31-38 of 1113")
	)
	(layers
		(0 "F.Cu" signal "TOP")
		(4 "In1.Cu" signal "L02_GND1")
		(6 "In2.Cu" signal "L03_SIG1")
		(8 "In3.Cu" signal "L04_GND2")
		(10 "In4.Cu" signal "L05_VCC1")
		(12 "In5.Cu" signal "L06_VCC2")
		(14 "In6.Cu" signal "L07_GND3")
		(16 "In7.Cu" signal "L08_SIG2")
		(18 "In8.Cu" signal "L09_GND4")
		(2 "B.Cu" signal "BOTTOM")
		(9 "F.Adhes" user "F.Adhesive")
		(11 "B.Adhes" user "B.Adhesive")
		(13 "F.Paste" user "Package Geometry/Pastemask Top")
		(15 "B.Paste" user "Package Geometry/Pastemask Bottom")
		(5 "F.SilkS" user "Ref Des/Silkscreen Top")
		(7 "B.SilkS" user "Ref Des/Silkscreen Bottom")
		(1 "F.Mask" user "Board Geometry/Soldermask Top")
		(3 "B.Mask" user "Board Geometry/Soldermask Bottom")
		(17 "Dwgs.User" user "User.Drawings")
		(19 "Cmts.User" user "User.Comments")
		(21 "Eco1.User" user "User.Eco1")
		(23 "Eco2.User" user "User.Eco2")
		(25 "Edge.Cuts" user "Board Geometry/Outline")
		(27 "Margin" user)
		(31 "F.CrtYd" user "Package Geometry/Place Bound Top")
		(29 "B.CrtYd" user "Package Geometry/Place Bound Bottom")
		(35 "F.Fab" user "Ref Des/Assembly Top")
		(33 "B.Fab" user "Ref Des/Assembly Bottom")
	)
	(footprint ""
		(layer "F.Cu")
		(at 79.8576 -45.72 180)
		(property "Reference" "R87"
			(at -0.0254 -14.13637 0)
			(unlocked yes)
			(layer "F.SilkS")
			(effects
				(font
					(size 0.7874 0.5842)
					(thickness 0.1524)
				)
			)
		)
		(property "Value" "VAL*"
			(at 0.02032 2.13233 180)
			(unlocked yes)
			(layer "F.Fab")
			(hide yes)
			(effects
				(font
					(size 0.7874 0.5842)
					(thickness 0.1524)
				)
			)
		)
		(property "Device Type" "RESISTOR-G155-100R0-J0,0OHM,-"
			(at 0.008382 1.210564 180)
			(unlocked yes)
			(layer "F.Fab")
			(hide yes)
			(effects
				(font
					(size 0.7874 0.5842)
					(thickness 0.1524)
				)
			)
		)
		(property "User Part Number" "PARTNUM*"
			(at 0.02032 4.024884 180)
			(unlocked yes)
			(layer "Cmts.User")
			(hide yes)
			(effects
				(font
					(size 0.7874 0.5842)
					(thickness 0.1524)
				)
			)
		)
		(property "Tolerance" "TOL*"
			(at 0.044704 3.05435 180)
			(unlocked yes)
			(layer "Cmts.User")
			(hide yes)
			(effects
				(font
					(size 0.7874 0.5842)
					(thickness 0.1524)
				)
			)
		)
		(duplicate_pad_numbers_are_jumpers no)
		(fp_line
			(start 1.143 0.5588)
			(end 1.143 -0.5588)
			(stroke
				(width 0.1)
				(type default)
			)
			(layer "F.SilkS")
		)
		(fp_line
			(start 1.143 -0.5588)
			(end -1.143 -0.5588)
			(stroke
				(width 0.1)
				(type default)
			)
			(layer "F.SilkS")
		)
		(fp_line
			(start -1.143 0.5588)
			(end 1.143 0.5588)
			(stroke
				(width 0.1)
				(type default)
			)
			(layer "F.SilkS")
		)
		(fp_line
			(start -1.143 -0.5588)
			(end -1.143 0.5588)
			(stroke
				(width 0.1)
				(type default)
			)
			(layer "F.SilkS")
		)
		(fp_rect
			(start 1.143 -0.5588)
			(end -1.143 0.5588)
			(stroke
				(width 0)
				(type default)
			)
			(fill no)
			(layer "F.CrtYd")
		)
		(fp_line
			(start 0.508 0.3048)
			(end 0.508 -0.3048)
			(stroke
				(width 0.1)
				(type default)
			)
			(layer "F.Fab")
		)
		(fp_line
			(start 0.508 -0.3048)
			(end -0.508 -0.3048)
			(stroke
				(width 0.1)
				(type default)
			)
			(layer "F.Fab")
		)
		(fp_line
			(start -0.508 0.3048)
			(end 0.508 0.3048)
			(stroke
				(width 0.1)
				(type default)
			)
			(layer "F.Fab")
		)
		(fp_line
			(start -0.508 -0.3048)
			(end -0.508 0.3048)
			(stroke
				(width 0.1)
				(type default)
			)
			(layer "F.Fab")
		)
		(pad "1" smd rect
			(at -0.5334 0 180)
			(size 0.7112 0.6096)
			(layers "F.Cu" "F.Mask" "F.Paste")
			(net "FPGA_IN_MAC_PPS_OUTP")
		)
		(pad "2" smd rect
			(at 0.5334 0 180)
			(size 0.7112 0.6096)
			(layers "F.Cu" "F.Mask" "F.Paste")
			(net "R_MAC_PPS_OUTP")
		)
		(zone
			(layer "F.Cu")
			(hatch none 0.5)
			(connect_pads
				(clearance 0)
			)
			(min_thickness 0.25)
			(keepout
				(tracks allowed)
				(vias not_allowed)
				(pads allowed)
				(copperpour not_allowed)
				(footprints allowed)
			)
			(placement
				(enabled no)
				(sheetname "")
			)
			(fill
				(thermal_gap 0.5)
				(thermal_bridge_width 0.5)
				(island_removal_mode 0)
			)
			(polygon
				(pts
					(xy 79.7814 -45.4152) (xy 79.9338 -45.4152) (xy 79.9338 -46.0248) (xy 79.7814 -46.0248)
				)
			)
		)
	)
	(footprint ""
		(layer "F.Cu")
		(at 55.245 -123.698)
		(property "Reference" "SP79"
			(at 0 0 0)
			(layer "F.SilkS")
			(hide yes)
			(effects
				(font
					(size 1.27 1.27)
				)
			)
		)
		(property "Value" ""
			(at 0 0 0)
			(layer "F.Fab")
			(effects
				(font
					(size 1.27 1.27)
				)
			)
		)
		(duplicate_pad_numbers_are_jumpers no)
	)
	(footprint ""
		(layer "F.Cu")
		(at 7.2898 -68.201032 90)
		(property "Reference" "R376"
			(at 3.553968 -0.39243 90)
			(unlocked yes)
			(layer "F.SilkS")
			(effects
				(font
					(size 0.7874 0.5842)
					(thickness 0.1524)
				)
			)
		)
		(property "Value" "VAL*"
			(at 0.02032 2.13233 90)
			(unlocked yes)
			(layer "F.Fab")
			(hide yes)
			(effects
				(font
					(size 0.7874 0.5842)
					(thickness 0.1524)
				)
			)
		)
		(property "Device Type" "RESISTOR-G155-11000-01,100OHM,A"
			(at 0.008382 1.210564 90)
			(unlocked yes)
			(layer "F.Fab")
			(hide yes)
			(effects
				(font
					(size 0.7874 0.5842)
					(thickness 0.1524)
				)
			)
		)
		(property "User Part Number" "PARTNUM*"
			(at 0.02032 4.024884 90)
			(unlocked yes)
			(layer "Cmts.User")
			(hide yes)
			(effects
				(font
					(size 0.7874 0.5842)
					(thickness 0.1524)
				)
			)
		)
		(property "Tolerance" "TOL*"
			(at 0.044704 3.05435 90)
			(unlocked yes)
			(layer "Cmts.User")
			(hide yes)
			(effects
				(font
					(size 0.7874 0.5842)
					(thickness 0.1524)
				)
			)
		)
		(duplicate_pad_numbers_are_jumpers no)
		(fp_line
			(start 1.143 -0.5588)
			(end -1.143 -0.5588)
			(stroke
				(width 0.1)
				(type default)
			)
			(layer "F.SilkS")
		)
		(fp_line
			(start -1.143 -0.5588)
			(end -1.143 0.5588)
			(stroke
				(width 0.1)
				(type default)
			)
			(layer "F.SilkS")
		)
		(fp_line
			(start 1.143 0.5588)
			(end 1.143 -0.5588)
			(stroke
				(width 0.1)
				(type default)
			)
			(layer "F.SilkS")
		)
		(fp_line
			(start -1.143 0.5588)
			(end 1.143 0.5588)
			(stroke
				(width 0.1)
				(type default)
			)
			(layer "F.SilkS")
		)
		(fp_poly
			(pts
				(xy -1.143 0.5588) (xy 1.143 0.5588) (xy 1.143 -0.5588) (xy -1.143 -0.5588)
			)
			(stroke
				(width 0)
				(type default)
			)
			(fill no)
			(layer "F.CrtYd")
		)
		(fp_line
			(start 0.508 -0.3048)
			(end -0.508 -0.3048)
			(stroke
				(width 0.1)
				(type default)
			)
			(layer "F.Fab")
		)
		(fp_line
			(start -0.508 -0.3048)
			(end -0.508 0.3048)
			(stroke
				(width 0.1)
				(type default)
			)
			(layer "F.Fab")
		)
		(fp_line
			(start 0.508 0.3048)
			(end 0.508 -0.3048)
			(stroke
				(width 0.1)
				(type default)
			)
			(layer "F.Fab")
		)
		(fp_line
			(start -0.508 0.3048)
			(end 0.508 0.3048)
			(stroke
				(width 0.1)
				(type default)
			)
			(layer "F.Fab")
		)
		(pad "1" smd rect
			(at -0.5334 0 90)
			(size 0.7112 0.6096)
			(layers "F.Cu" "F.Mask" "F.Paste")
			(net "FPGA_OUT_SMA3_LED_RED_N")
		)
		(pad "2" smd rect
			(at 0.5334 0 90)
			(size 0.7112 0.6096)
			(layers "F.Cu" "F.Mask" "F.Paste")
			(net "UNNAMED_14_LED4PV14_I267_3")
		)
		(zone
			(layer "F.Cu")
			(hatch none 0.5)
			(connect_pads
				(clearance 0)
			)
			(min_thickness 0.25)
			(keepout
				(tracks not_allowed)
				(vias allowed)
				(pads allowed)
				(copperpour not_allowed)
				(footprints allowed)
			)
			(placement
				(enabled no)
				(sheetname "")
			)
			(fill
				(thermal_gap 0.5)
				(thermal_bridge_width 0.5)
				(island_removal_mode 0)
			)
			(polygon
				(pts
					(xy 7.5946 -68.124832) (xy 7.5946 -68.277232) (xy 6.985 -68.277232) (xy 6.985 -68.124832)
				)
			)
		)
		(zone
			(layer "F.Cu")
			(hatch none 0.5)
			(connect_pads
				(clearance 0)
			)
			(min_thickness 0.25)
			(keepout
				(tracks allowed)
				(vias not_allowed)
				(pads allowed)
				(copperpour not_allowed)
				(footprints allowed)
			)
			(placement
				(enabled no)
				(sheetname "")
			)
			(fill
				(thermal_gap 0.5)
				(thermal_bridge_width 0.5)
				(island_removal_mode 0)
			)
			(polygon
				(pts
					(xy 7.5946 -68.124832) (xy 7.5946 -68.277232) (xy 6.985 -68.277232) (xy 6.985 -68.124832)
				)
			)
		)
	)
	(footprint ""
		(layer "F.Cu")
		(at 66.04 -126.873)
		(property "Reference" "SP49"
			(at 0 0 0)
			(layer "F.SilkS")
			(hide yes)
			(effects
				(font
					(size 1.27 1.27)
				)
			)
		)
		(property "Value" ""
			(at 0 0 0)
			(layer "F.Fab")
			(effects
				(font
					(size 1.27 1.27)
				)
			)
		)
		(duplicate_pad_numbers_are_jumpers no)
	)
	(footprint ""
		(layer "F.Cu")
		(at 13.899896 -61.60008 -90)
		(property "Reference" "U15"
			(at -0.88392 2.430526 90)
			(unlocked yes)
			(layer "F.SilkS")
			(effects
				(font
					(size 0.7874 0.5842)
					(thickness 0.1524)
				)
			)
		)
		(property "Value" ""
			(at 0 0 270)
			(layer "F.Fab")
			(effects
				(font
					(size 1.27 1.27)
				)
			)
		)
		(property "User Part Number" "PARTNUM*"
			(at 0 3.6068 270)
			(unlocked yes)
			(layer "Cmts.User")
			(hide yes)
			(effects
				(font
					(size 0.7874 0.5842)
					(thickness 0.1524)
				)
			)
		)
		(property "Device Type" "74HCT2G125DP_TSSOP8-G220-00055A"
			(at 0 2.413 270)
			(unlocked yes)
			(layer "F.Fab")
			(hide yes)
			(effects
				(font
					(size 0.7874 0.5842)
					(thickness 0.1524)
				)
			)
		)
		(duplicate_pad_numbers_are_jumpers no)
		(fp_line
			(start -2.426716 1.304036)
			(end -2.426716 -1.304036)
			(stroke
				(width 0.1)
				(type default)
			)
			(layer "F.SilkS")
		)
		(fp_line
			(start 2.426716 1.304036)
			(end -2.426716 1.304036)
			(stroke
				(width 0.1)
				(type default)
			)
			(layer "F.SilkS")
		)
		(fp_line
			(start -2.426716 -1.304036)
			(end 2.426716 -1.304036)
			(stroke
				(width 0.1)
				(type default)
			)
			(layer "F.SilkS")
		)
		(fp_line
			(start 2.426716 -1.304036)
			(end 2.426716 1.304036)
			(stroke
				(width 0.1)
				(type default)
			)
			(layer "F.SilkS")
		)
		(fp_poly
			(pts
				(arc
					(start -3.21437 -1.465326)
					(mid -3.21437 -0.703326)
					(end -3.21437 -1.465326)
				)
			)
			(stroke
				(width 0)
				(type default)
			)
			(fill yes)
			(layer "F.SilkS")
		)
		(fp_poly
			(pts
				(xy -2.680716 1.558036) (xy 2.680716 1.558036) (xy 2.680716 -1.558036) (xy -2.680716 -1.558036)
			)
			(stroke
				(width 0)
				(type default)
			)
			(fill no)
			(layer "F.CrtYd")
		)
		(fp_line
			(start -1.199896 1.050036)
			(end 1.199896 1.050036)
			(stroke
				(width 0.1)
				(type default)
			)
			(layer "F.Fab")
		)
		(fp_line
			(start 1.199896 1.050036)
			(end 1.199896 -1.050036)
			(stroke
				(width 0.1)
				(type default)
			)
			(layer "F.Fab")
		)
		(fp_line
			(start -1.199896 -1.050036)
			(end -1.199896 1.050036)
			(stroke
				(width 0.1)
				(type default)
			)
			(layer "F.Fab")
		)
		(fp_line
			(start 1.199896 -1.050036)
			(end -1.199896 -1.050036)
			(stroke
				(width 0.1)
				(type default)
			)
			(layer "F.Fab")
		)
		(fp_poly
			(pts
				(arc
					(start -2.02692 -1.721104)
					(mid -2.02692 -0.959104)
					(end -2.02692 -1.721104)
				)
			)
			(stroke
				(width 0)
				(type default)
			)
			(fill yes)
			(layer "F.Fab")
		)
		(fp_text user "4"
			(at -1.53797 1.707896 0)
			(unlocked yes)
			(layer "F.SilkS")
			(effects
				(font
					(size 0.635 0.4064)
					(thickness 0.1524)
				)
			)
		)
		(fp_text user "5"
			(at 2.78003 1.580896 0)
			(unlocked yes)
			(layer "F.SilkS")
			(effects
				(font
					(size 0.635 0.4064)
					(thickness 0.1524)
				)
			)
		)
		(fp_text user "8"
			(at 2.70383 -1.594104 0)
			(unlocked yes)
			(layer "F.SilkS")
			(effects
				(font
					(size 0.635 0.4064)
					(thickness 0.1524)
				)
			)
		)
		(fp_text user "5"
			(at 1.816608 1.326896 0)
			(unlocked yes)
			(layer "F.Fab")
			(effects
				(font
					(size 0.7874 0.5842)
					(thickness 0.1524)
				)
			)
		)
		(fp_text user "4"
			(at -1.993392 1.199896 0)
			(unlocked yes)
			(layer "F.Fab")
			(effects
				(font
					(size 0.7874 0.5842)
					(thickness 0.1524)
				)
			)
		)
		(fp_text user "8"
			(at 1.94945 -1.340104 0)
			(unlocked yes)
			(layer "F.Fab")
			(effects
				(font
					(size 0.7874 0.5842)
					(thickness 0.1524)
				)
			)
		)
		(pad "1" smd rect
			(at -1.690116 -0.749808 270)
			(size 0.9652 0.3048)
			(layers "F.Cu" "F.Mask" "F.Paste")
			(net "SMA1_SIG_OUT_BF_EN_N")
		)
		(pad "2" smd rect
			(at -1.690116 -0.249936 270)
			(size 0.9652 0.3048)
			(layers "F.Cu" "F.Mask" "F.Paste")
			(net "UNNAMED_12_74HCT2G125DPTSSOP8_6")
		)
		(pad "3" smd rect
			(at -1.690116 0.249936 270)
			(size 0.9652 0.3048)
			(layers "F.Cu" "F.Mask" "F.Paste")
			(net "BF_ANT1_IN")
		)
		(pad "4" smd rect
			(at -1.690116 0.749808 270)
			(size 0.9652 0.3048)
			(layers "F.Cu" "F.Mask" "F.Paste")
			(net "SG")
		)
		(pad "5" smd rect
			(at 1.690116 0.749808 270)
			(size 0.9652 0.3048)
			(layers "F.Cu" "F.Mask" "F.Paste")
			(net "BF_SMA1_SIG_IO_CONN")
		)
		(pad "6" smd rect
			(at 1.690116 0.249936 270)
			(size 0.9652 0.3048)
			(layers "F.Cu" "F.Mask" "F.Paste")
			(net "BF_SMA1_SIG_IO_CONN")
		)
		(pad "7" smd rect
			(at 1.690116 -0.249936 270)
			(size 0.9652 0.3048)
			(layers "F.Cu" "F.Mask" "F.Paste")
			(net "SMA1_SIG_IN_BF_EN_N")
		)
		(pad "8" smd rect
			(at 1.690116 -0.749808 270)
			(size 0.9652 0.3048)
			(layers "F.Cu" "F.Mask" "F.Paste")
			(net "XP3R3V_FPGA")
		)
	)
	(footprint ""
		(layer "F.Cu")
		(at 57.15 -122.047)
		(property "Reference" "SP44"
			(at 0 0 0)
			(layer "F.SilkS")
			(hide yes)
			(effects
				(font
					(size 1.27 1.27)
				)
			)
		)
		(property "Value" ""
			(at 0 0 0)
			(layer "F.Fab")
			(effects
				(font
					(size 1.27 1.27)
				)
			)
		)
		(duplicate_pad_numbers_are_jumpers no)
	)
	(footprint ""
		(layer "F.Cu")
		(at 141.732 -41.021)
		(property "Reference" "TP54"
			(at -1.8542 1.18237 0)
			(unlocked yes)
			(layer "F.SilkS")
			(effects
				(font
					(size 0.7874 0.5842)
					(thickness 0.1524)
				)
				(justify left)
			)
		)
		(property "Value" ""
			(at 0 0 0)
			(layer "F.Fab")
			(effects
				(font
					(size 1.27 1.27)
				)
			)
		)
		(property "Device Type" "TP_PIONT-TP010CT020B030_PTH-TPA"
			(at -1.341882 0.996696 0)
			(unlocked yes)
			(layer "F.Fab")
			(hide yes)
			(effects
				(font
					(size 0.7874 0.5842)
					(thickness 0.1524)
				)
				(justify left)
			)
		)
		(duplicate_pad_numbers_are_jumpers no)
		(fp_poly
			(pts
				(arc
					(start 0.889 0)
					(mid -0.889 0)
					(end 0.889 0)
				)
			)
			(stroke
				(width 0)
				(type default)
			)
			(fill no)
			(layer "B.CrtYd")
		)
		(fp_poly
			(pts
				(arc
					(start 0.889 0)
					(mid -0.889 0)
					(end 0.889 0)
				)
			)
			(stroke
				(width 0)
				(type default)
			)
			(fill no)
			(layer "F.CrtYd")
		)
		(pad "1" thru_hole circle
			(at 0 0)
			(size 0.508 0.508)
			(drill 0.254)
			(layers "*.Cu" "*.Mask")
			(remove_unused_layers no)
			(net "XP1R0V_FPGA")
			(clearance 0.1016)
			(padstack
				(mode front_inner_back)
				(layer "Inner"
					(shape circle)
					(size 0.508 0.508)
					(clearance 0.1016)
				)
				(layer "B.Cu"
					(shape circle)
					(size 0.762 0.762)
					(clearance -0.0254)
				)
			)
		)
	)
	(footprint ""
		(layer "F.Cu")
		(at 26.797 -94.234 -90)
		(property "Reference" "R456"
			(at -4.953 0.34163 90)
			(unlocked yes)
			(layer "F.SilkS")
			(effects
				(font
					(size 0.7874 0.5842)
					(thickness 0.1524)
				)
			)
		)
		(property "Value" "VAL*"
			(at 0.02032 2.13233 270)
			(unlocked yes)
			(layer "F.Fab")
			(hide yes)
			(effects
				(font
					(size 0.7874 0.5842)
					(thickness 0.1524)
				)
			)
		)
		(property "Tolerance" "TOL*"
			(at 0.044704 3.05435 270)
			(unlocked yes)
			(layer "Cmts.User")
			(hide yes)
			(effects
				(font
					(size 0.7874 0.5842)
					(thickness 0.1524)
				)
			)
		)
		(property "User Part Number" "PARTNUM*"
			(at 0.02032 4.024884 270)
			(unlocked yes)
			(layer "Cmts.User")
			(hide yes)
			(effects
				(font
					(size 0.7874 0.5842)
					(thickness 0.1524)
				)
			)
		)
		(property "Device Type" "RESISTOR-G155-11000-01,100OHM,A"
			(at 0.008382 1.210564 270)
			(unlocked yes)
			(layer "F.Fab")
			(hide yes)
			(effects
				(font
					(size 0.7874 0.5842)
					(thickness 0.1524)
				)
			)
		)
		(duplicate_pad_numbers_are_jumpers no)
		(fp_line
			(start -1.143 0.5588)
			(end 1.143 0.5588)
			(stroke
				(width 0.1)
				(type default)
			)
			(layer "F.SilkS")
		)
		(fp_line
			(start 1.143 0.5588)
			(end 1.143 -0.5588)
			(stroke
				(width 0.1)
				(type default)
			)
			(layer "F.SilkS")
		)
		(fp_line
			(start -1.143 -0.5588)
			(end -1.143 0.5588)
			(stroke
				(width 0.1)
				(type default)
			)
			(layer "F.SilkS")
		)
		(fp_line
			(start 1.143 -0.5588)
			(end -1.143 -0.5588)
			(stroke
				(width 0.1)
				(type default)
			)
			(layer "F.SilkS")
		)
		(fp_poly
			(pts
				(xy -1.143 0.5588) (xy 1.143 0.5588) (xy 1.143 -0.5588) (xy -1.143 -0.5588)
			)
			(stroke
				(width 0)
				(type default)
			)
			(fill no)
			(layer "F.CrtYd")
		)
		(fp_line
			(start -0.508 0.3048)
			(end 0.508 0.3048)
			(stroke
				(width 0.1)
				(type default)
			)
			(layer "F.Fab")
		)
		(fp_line
			(start 0.508 0.3048)
			(end 0.508 -0.3048)
			(stroke
				(width 0.1)
				(type default)
			)
			(layer "F.Fab")
		)
		(fp_line
			(start -0.508 -0.3048)
			(end -0.508 0.3048)
			(stroke
				(width 0.1)
				(type default)
			)
			(layer "F.Fab")
		)
		(fp_line
			(start 0.508 -0.3048)
			(end -0.508 -0.3048)
			(stroke
				(width 0.1)
				(type default)
			)
			(layer "F.Fab")
		)
		(pad "1" smd rect
			(at -0.5334 0 270)
			(size 0.7112 0.6096)
			(layers "F.Cu" "F.Mask" "F.Paste")
			(net "XP3R3V_FT_PG")
		)
		(pad "2" smd rect
			(at 0.5334 0 270)
			(size 0.7112 0.6096)
			(layers "F.Cu" "F.Mask" "F.Paste")
			(net "FT_USB_DETECT")
		)
		(zone
			(layer "F.Cu")
			(hatch none 0.5)
			(connect_pads
				(clearance 0)
			)
			(min_thickness 0.25)
			(keepout
				(tracks allowed)
				(vias not_allowed)
				(pads allowed)
				(copperpour not_allowed)
				(footprints allowed)
			)
			(placement
				(enabled no)
				(sheetname "")
			)
			(fill
				(thermal_gap 0.5)
				(thermal_bridge_width 0.5)
				(island_removal_mode 0)
			)
			(polygon
				(pts
					(xy 26.4922 -94.3102) (xy 26.4922 -94.1578) (xy 27.1018 -94.1578) (xy 27.1018 -94.3102)
				)
			)
		)
		(zone
			(layer "F.Cu")
			(hatch none 0.5)
			(connect_pads
				(clearance 0)
			)
			(min_thickness 0.25)
			(keepout
				(tracks not_allowed)
				(vias allowed)
				(pads allowed)
				(copperpour not_allowed)
				(footprints allowed)
			)
			(placement
				(enabled no)
				(sheetname "")
			)
			(fill
				(thermal_gap 0.5)
				(thermal_bridge_width 0.5)
				(island_removal_mode 0)
			)
			(polygon
				(pts
					(xy 26.4922 -94.3102) (xy 26.4922 -94.1578) (xy 27.1018 -94.1578) (xy 27.1018 -94.3102)
				)
			)
		)
	)
)
